# T6G (Grand Teton) — schematic netlist excerpt (pin names and nets, part order shuffled) for the footprints in the layout excerpt that follows; sources: Cadence DE-HDL packaged netlist, KiCad conversion of 04192023_DAF0TMB3IC0_F0TG_MB_C_brd_V02_OCP.brd

C2563  Q_CAP  22UF 4V 20% X6S  pkg C0402  page 70 : A = PVDDCR_SOC_P0 ; B = GND
C2020  Q_CAP  0.1UF 25V 10% X7R  pkg 0402  page 237 : A = VSENSE_P12V_INA230_3_INP ; B = VSENSE_P12V_INA230_3_INN
R1405  Q_RES  1K 1% EMPTY  pkg 0201LF  page 298 : A = P1V8_CPU0_RT_1D ; B = RXDET_BYP_RT_CPU0_P2

(kicad_pcb
	(version 20260206)
	(generator "pcbnew")
	(generator_version "10.0")
	(general
		(thickness 1.6)
		(legacy_teardrops no)
	)
	(paper "A4")
	(title_block
		(title "04192023_DAF0TMB3IC0_F0TG_MB_C_brd_V02_OCP.brd")
		(comment 1 "Grand Teton / footprints 410-412 of 8354")
	)
	(layers
		(0 "F.Cu" signal "TOP")
		(4 "In1.Cu" signal "GND")
		(6 "In2.Cu" signal "IN1")
		(8 "In3.Cu" signal "GND1")
		(10 "In4.Cu" signal "IN2")
		(12 "In5.Cu" signal "GND2")
		(14 "In6.Cu" signal "IN3")
		(16 "In7.Cu" signal "GND3")
		(18 "In8.Cu" signal "VCC")
		(20 "In9.Cu" signal "VCC1")
		(22 "In10.Cu" signal "GND4")
		(24 "In11.Cu" signal "IN4")
		(26 "In12.Cu" signal "GND5")
		(28 "In13.Cu" signal "IN5")
		(30 "In14.Cu" signal "GND6")
		(32 "In15.Cu" signal "IN6")
		(34 "In16.Cu" signal "GND7")
		(2 "B.Cu" signal "BOTTOM")
		(9 "F.Adhes" user "F.Adhesive")
		(11 "B.Adhes" user "B.Adhesive")
		(13 "F.Paste" user "Package Geometry/Pastemask Top")
		(15 "B.Paste" user "Package Geometry/Pastemask Bottom")
		(5 "F.SilkS" user "Ref Des/Silkscreen Top")
		(7 "B.SilkS" user "Ref Des/Silkscreen Bottom")
		(1 "F.Mask" user "Board Geometry/Soldermask Top")
		(3 "B.Mask" user "Board Geometry/Soldermask Bottom")
		(17 "Dwgs.User" user "User.Drawings")
		(19 "Cmts.User" user "User.Comments")
		(21 "Eco1.User" user "User.Eco1")
		(23 "Eco2.User" user "User.Eco2")
		(25 "Edge.Cuts" user "Board Geometry/Outline")
		(27 "Margin" user)
		(31 "F.CrtYd" user "Package Geometry/Place Bound Top")
		(29 "B.CrtYd" user "Package Geometry/Place Bound Bottom")
		(35 "F.Fab" user "Ref Des/Assembly Top")
		(33 "B.Fab" user "Ref Des/Assembly Bottom")
	)
	(footprint ""
		(layer "F.Cu")
		(at 78.826106 -58.382154 -90)
		(property "Reference" "C2020"
			(at 0 0 270)
			(layer "F.SilkS")
			(hide yes)
			(effects
				(font
					(size 1.27 1.27)
				)
			)
		)
		(property "Value" ""
			(at 0 0 270)
			(layer "F.Fab")
			(effects
				(font
					(size 1.27 1.27)
				)
			)
		)
		(duplicate_pad_numbers_are_jumpers no)
		(fp_line
			(start -0.7874 0.4064)
			(end -0.7874 -0.4064)
			(stroke
				(width 0.1524)
				(type default)
			)
			(layer "F.SilkS")
		)
		(fp_line
			(start 0.7874 0.4064)
			(end -0.7874 0.4064)
			(stroke
				(width 0.1524)
				(type default)
			)
			(layer "F.SilkS")
		)
		(fp_line
			(start -0.7874 -0.4064)
			(end 0.7874 -0.4064)
			(stroke
				(width 0.1524)
				(type default)
			)
			(layer "F.SilkS")
		)
		(fp_line
			(start 0.7874 -0.4064)
			(end 0.7874 0.4064)
			(stroke
				(width 0.1524)
				(type default)
			)
			(layer "F.SilkS")
		)
		(fp_line
			(start -0.67945 0.3048)
			(end -0.67945 -0.305054)
			(stroke
				(width 0.1)
				(type default)
			)
			(layer "F.Fab")
		)
		(fp_line
			(start -0.12065 0.3048)
			(end -0.67945 0.3048)
			(stroke
				(width 0.1)
				(type default)
			)
			(layer "F.Fab")
		)
		(fp_line
			(start 0.120396 0.3048)
			(end 0.120396 0.2794)
			(stroke
				(width 0.1)
				(type default)
			)
			(layer "F.Fab")
		)
		(fp_line
			(start 0.67945 0.3048)
			(end 0.120396 0.3048)
			(stroke
				(width 0.1)
				(type default)
			)
			(layer "F.Fab")
		)
		(fp_line
			(start -0.12065 0.2794)
			(end -0.12065 0.3048)
			(stroke
				(width 0.1)
				(type default)
			)
			(layer "F.Fab")
		)
		(fp_line
			(start 0.120396 0.2794)
			(end -0.12065 0.2794)
			(stroke
				(width 0.1)
				(type default)
			)
			(layer "F.Fab")
		)
		(fp_line
			(start -0.12065 -0.2794)
			(end 0.12065 -0.2794)
			(stroke
				(width 0.1)
				(type default)
			)
			(layer "F.Fab")
		)
		(fp_line
			(start 0.12065 -0.2794)
			(end 0.12065 -0.3048)
			(stroke
				(width 0.1)
				(type default)
			)
			(layer "F.Fab")
		)
		(fp_line
			(start 0.12065 -0.3048)
			(end 0.67945 -0.3048)
			(stroke
				(width 0.1)
				(type default)
			)
			(layer "F.Fab")
		)
		(fp_line
			(start 0.67945 -0.3048)
			(end 0.67945 0.3048)
			(stroke
				(width 0.1)
				(type default)
			)
			(layer "F.Fab")
		)
		(fp_line
			(start -0.67945 -0.305054)
			(end -0.12065 -0.305054)
			(stroke
				(width 0.1)
				(type default)
			)
			(layer "F.Fab")
		)
		(fp_line
			(start -0.12065 -0.305054)
			(end -0.12065 -0.2794)
			(stroke
				(width 0.1)
				(type default)
			)
			(layer "F.Fab")
		)
		(pad "1" smd circle
			(at -0.40005 0 270)
			(size 0 0)
			(layers "F.Cu" "F.Mask" "F.Paste")
			(net "VSENSE_P12V_INA230_3_INP")
		)
		(pad "2" smd circle
			(at 0.40005 0 270)
			(size 0 0)
			(layers "F.Cu" "F.Mask" "F.Paste")
			(net "VSENSE_P12V_INA230_3_INN")
		)
	)
	(footprint ""
		(layer "F.Cu")
		(at 363.645958 -258.795012)
		(property "Reference" "C2563"
			(at 0 0 0)
			(layer "F.SilkS")
			(hide yes)
			(effects
				(font
					(size 1.27 1.27)
				)
			)
		)
		(property "Value" ""
			(at 0 0 0)
			(layer "F.Fab")
			(effects
				(font
					(size 1.27 1.27)
				)
			)
		)
		(duplicate_pad_numbers_are_jumpers no)
		(fp_line
			(start -0.7874 -0.4064)
			(end 0.7874 -0.4064)
			(stroke
				(width 0.1524)
				(type default)
			)
			(layer "F.SilkS")
		)
		(fp_line
			(start -0.7874 0.4064)
			(end -0.7874 -0.4064)
			(stroke
				(width 0.1524)
				(type default)
			)
			(layer "F.SilkS")
		)
		(fp_line
			(start 0.7874 -0.4064)
			(end 0.7874 0.4064)
			(stroke
				(width 0.1524)
				(type default)
			)
			(layer "F.SilkS")
		)
		(fp_line
			(start 0.7874 0.4064)
			(end -0.7874 0.4064)
			(stroke
				(width 0.1524)
				(type default)
			)
			(layer "F.SilkS")
		)
		(fp_line
			(start -0.67945 -0.305054)
			(end -0.12065 -0.305054)
			(stroke
				(width 0.1)
				(type default)
			)
			(layer "F.Fab")
		)
		(fp_line
			(start -0.67945 0.3048)
			(end -0.67945 -0.305054)
			(stroke
				(width 0.1)
				(type default)
			)
			(layer "F.Fab")
		)
		(fp_line
			(start -0.12065 -0.305054)
			(end -0.12065 -0.2794)
			(stroke
				(width 0.1)
				(type default)
			)
			(layer "F.Fab")
		)
		(fp_line
			(start -0.12065 -0.2794)
			(end 0.12065 -0.2794)
			(stroke
				(width 0.1)
				(type default)
			)
			(layer "F.Fab")
		)
		(fp_line
			(start -0.12065 0.2794)
			(end -0.12065 0.3048)
			(stroke
				(width 0.1)
				(type default)
			)
			(layer "F.Fab")
		)
		(fp_line
			(start -0.12065 0.3048)
			(end -0.67945 0.3048)
			(stroke
				(width 0.1)
				(type default)
			)
			(layer "F.Fab")
		)
		(fp_line
			(start 0.120396 0.2794)
			(end -0.12065 0.2794)
			(stroke
				(width 0.1)
				(type default)
			)
			(layer "F.Fab")
		)
		(fp_line
			(start 0.120396 0.3048)
			(end 0.120396 0.2794)
			(stroke
				(width 0.1)
				(type default)
			)
			(layer "F.Fab")
		)
		(fp_line
			(start 0.12065 -0.3048)
			(end 0.67945 -0.3048)
			(stroke
				(width 0.1)
				(type default)
			)
			(layer "F.Fab")
		)
		(fp_line
			(start 0.12065 -0.2794)
			(end 0.12065 -0.3048)
			(stroke
				(width 0.1)
				(type default)
			)
			(layer "F.Fab")
		)
		(fp_line
			(start 0.67945 -0.3048)
			(end 0.67945 0.3048)
			(stroke
				(width 0.1)
				(type default)
			)
			(layer "F.Fab")
		)
		(fp_line
			(start 0.67945 0.3048)
			(end 0.120396 0.3048)
			(stroke
				(width 0.1)
				(type default)
			)
			(layer "F.Fab")
		)
		(pad "1" smd circle
			(at -0.40005 0)
			(size 0 0)
			(layers "F.Cu" "F.Mask" "F.Paste")
			(net "PVDDCR_SOC_P0")
		)
		(pad "2" smd circle
			(at 0.40005 0)
			(size 0 0)
			(layers "F.Cu" "F.Mask" "F.Paste")
			(net "GND")
		)
	)
	(footprint ""
		(layer "F.Cu")
		(at 432.308 -405.9174)
		(property "Reference" "R1405"
			(at 0 0 0)
			(layer "F.SilkS")
			(hide yes)
			(effects
				(font
					(size 1.27 1.27)
				)
			)
		)
		(property "Value" ""
			(at 0 0 0)
			(layer "F.Fab")
			(effects
				(font
					(size 1.27 1.27)
				)
			)
		)
		(duplicate_pad_numbers_are_jumpers no)
		(fp_line
			(start -0.32512 -0.175006)
			(end 0.32512 -0.175006)
			(stroke
				(width 0.1)
				(type default)
			)
			(layer "F.Fab")
		)
		(fp_line
			(start -0.32512 0.175006)
			(end -0.32512 -0.175006)
			(stroke
				(width 0.1)
				(type default)
			)
			(layer "F.Fab")
		)
		(fp_line
			(start 0.32512 -0.175006)
			(end 0.32512 0.175006)
			(stroke
				(width 0.1)
				(type default)
			)
			(layer "F.Fab")
		)
		(fp_line
			(start 0.32512 0.175006)
			(end -0.32512 0.175006)
			(stroke
				(width 0.1)
				(type default)
			)
			(layer "F.Fab")
		)
		(pad "1" smd rect
			(at -0.2667 0)
			(size 0.3048 0.381)
			(layers "F.Cu" "F.Mask" "F.Paste")
			(net "P1V8_CPU0_RT_1D")
		)
		(pad "2" smd rect
			(at 0.2667 0 180)
			(size 0.3048 0.381)
			(layers "F.Cu" "F.Mask" "F.Paste")
			(net "RXDET_BYP_RT_CPU0_P2")
		)
	)
)
